FILE_TYPE = MACRO_DRAWING;
SET COLOR_WIRE YELLOW;
SET COLOR_PROP ORANGE;
SET COLOR_DOT WHITE;
SET COLOR_ARC YELLOW;
SET COLOR_BODY GREEN;
SET COLOR_NOTE PURPLE;
SET PROP_DISPLAY VALUE;
SET PAGE_NUMBER P146;
FORCEADD QUANTA_TITLE_BLOCK_C..1
(-575 -600);
FORCEPROP 1 LAST CUSTOM_TXT_CDS <NAME_2>
J 0
(-3750 -550);
FORCEPROP 1 LAST CUSTOM_TXT_CDS <NAME_1>
J 0
(-3750 -425);
FORCEPROP 1 LAST CUSTOM_TXT_CDS <Q_NUMBER>
J 0
(-1978 -497);
DISPLAY 1.212766 (-1978 -497);
FORCEPROP 1 LAST CUSTOM_TXT_CDS <Q_PROJ>
J 0
(-2957 -498);
DISPLAY 1.212766 (-2957 -498);
FORCEPROP 1 LAST CUSTOM_TXT_CDS <Q_REV>
J 0
(-759 -497);
DISPLAY 1.212766 (-759 -497);
FORCEPROP 1 LAST CUSTOM_TXT_CDS <CON_LAST_MODIFIED>
J 0
(-2460 -585);
DISPLAY 0.978723 (-2460 -585);
FORCEPROP 1 LAST CUSTOM_TXT_CDS <CON_PAGE_NUM> OF <CON_TOTAL_PAGES>
J 0
(-1021 -582);
DISPLAY 0.978723 (-1021 -582);
FORCEPROP 1 LAST Q_TITLE USB CONDITIONER
J 0
(-9850 -550);
DISPLAY 2.446809 (-9850 -550);
PAINT GREEN (-9850 -550);
FORCEPROP 1 LAST Q_DEPT BU9
J 1
(-4338 -551);
DISPLAY 1.957447 (-4338 -551);
PAINT GREEN (-4338 -551);
FORCEPROP 2 LAST CDS_LIB pure_quanta
J 0
(-575 -600);
DISPLAY INVISIBLE (-575 -600);
FORCEPROP 1 LAST CDS_LMAN_SYM_OUTLINE -9475,6775,100,-125
J 0
(-575 -600);
DISPLAY 0.468085 (-575 -600);
PAINT GREEN (-575 -600);
DISPLAY INVISIBLE (-575 -600);
FORCEPROP 2 LAST PAGE_BORDER TRUE
J 0
(-8465 4650);
DISPLAY 0.638298 (-8465 4650);
PAINT PINK (-8465 4650);
DISPLAY INVISIBLE (-8465 4650);
FORCEPROP 1 LAST COMMENT_BODY TRUE
J 0
(-563 -613);
DISPLAY 0.978723 (-563 -613);
PAINT GREEN (-563 -613);
DISPLAY INVISIBLE (-563 -613);
FORCEPROP 2 LAST CDS_XR_PAGE_TITLE CR-146 : @T6G_MB_LIB.T6G(SCH_1):PAGE146
J 0
(-8465 4650);
DISPLAY 0.638298 (-8465 4650);
PAINT PINK (-8465 4650);
DISPLAY INVISIBLE (-8465 4650);
FORCEPROP 2 LAST CUSTOM_TXT_CDS <XR_PAGE_TITLE>
J 0
(-8465 4650);
DISPLAY 0.638298 (-8465 4650);
PAINT PINK (-8465 4650);
DISPLAY INVISIBLE (-8465 4650);
FORCEPROP 0 LAST CDS_CON_LAST_MODIFIED Wed Mar 09 20:18:46 2022
J 0
(-2460 -585);
DISPLAY INVISIBLE (-2460 -585);
QUIT
